# S9S_MB_2U (Grand Teton) — schematic netlist excerpt (pin names and nets, part order shuffled) for the footprints in the layout excerpt that follows; sources: Cadence DE-HDL packaged netlist, KiCad conversion of 03242023_DA0F0TMBIJ0_F0T_Motherboard_J_brd_V01_OCP.brd

R4554  Q_RES  4.7K 5% CHIP  pkg 0402LF  page 246 : A = P3V3_AUX ; B = HPDB_HSC_PWRGD_ISO
R3484  Q_RES  33.2 1% CHIP  pkg 0402LF  page 213 : A = GPU_FPGA_OVERT_ISO_N ; B = GPU_FPGA_OVERT_ISO_R_N

(kicad_pcb
	(version 20260206)
	(generator "pcbnew")
	(generator_version "10.0")
	(general
		(thickness 1.6)
		(legacy_teardrops no)
	)
	(paper "A4")
	(title_block
		(title "03242023_DA0F0TMBIJ0_F0T_Motherboard_J_brd_V01_OCP.brd")
		(comment 1 "Grand Teton / footprints 3274-3275 of 6105")
	)
	(layers
		(0 "F.Cu" signal "TOP")
		(4 "In1.Cu" signal "GND")
		(6 "In2.Cu" signal "IN1")
		(8 "In3.Cu" signal "GND1")
		(10 "In4.Cu" signal "IN2")
		(12 "In5.Cu" signal "GND2")
		(14 "In6.Cu" signal "IN3")
		(16 "In7.Cu" signal "GND3")
		(18 "In8.Cu" signal "VCC")
		(20 "In9.Cu" signal "VCC1")
		(22 "In10.Cu" signal "GND4")
		(24 "In11.Cu" signal "IN4")
		(26 "In12.Cu" signal "GND5")
		(28 "In13.Cu" signal "IN5")
		(30 "In14.Cu" signal "GND6")
		(32 "In15.Cu" signal "IN6")
		(34 "In16.Cu" signal "GND7")
		(2 "B.Cu" signal "BOTTOM")
		(9 "F.Adhes" user "F.Adhesive")
		(11 "B.Adhes" user "B.Adhesive")
		(13 "F.Paste" user "Package Geometry/Pastemask Top")
		(15 "B.Paste" user "Package Geometry/Pastemask Bottom")
		(5 "F.SilkS" user "Ref Des/Silkscreen Top")
		(7 "B.SilkS" user "Ref Des/Silkscreen Bottom")
		(1 "F.Mask" user "Board Geometry/Soldermask Top")
		(3 "B.Mask" user "Board Geometry/Soldermask Bottom")
		(17 "Dwgs.User" user "User.Drawings")
		(19 "Cmts.User" user "User.Comments")
		(21 "Eco1.User" user "User.Eco1")
		(23 "Eco2.User" user "User.Eco2")
		(25 "Edge.Cuts" user "Board Geometry/Outline")
		(27 "Margin" user)
		(31 "F.CrtYd" user "Package Geometry/Place Bound Top")
		(29 "B.CrtYd" user "Package Geometry/Place Bound Bottom")
		(35 "F.Fab" user "Ref Des/Assembly Top")
		(33 "B.Fab" user "Ref Des/Assembly Bottom")
	)
	(footprint ""
		(layer "F.Cu")
		(at 285.714948 -411.2895 90)
		(property "Reference" "R4554"
			(at 0 0 90)
			(layer "F.SilkS")
			(hide yes)
			(effects
				(font
					(size 1.27 1.27)
				)
			)
		)
		(property "Value" ""
			(at 0 0 90)
			(layer "F.Fab")
			(effects
				(font
					(size 1.27 1.27)
				)
			)
		)
		(duplicate_pad_numbers_are_jumpers no)
		(fp_line
			(start 0.7874 -0.4064)
			(end 0.7874 0.4064)
			(stroke
				(width 0.1524)
				(type default)
			)
			(layer "F.SilkS")
		)
		(fp_line
			(start -0.7874 -0.4064)
			(end 0.7874 -0.4064)
			(stroke
				(width 0.1524)
				(type default)
			)
			(layer "F.SilkS")
		)
		(fp_line
			(start 0.7874 0.4064)
			(end -0.7874 0.4064)
			(stroke
				(width 0.1524)
				(type default)
			)
			(layer "F.SilkS")
		)
		(fp_line
			(start -0.7874 0.4064)
			(end -0.7874 -0.4064)
			(stroke
				(width 0.1524)
				(type default)
			)
			(layer "F.SilkS")
		)
		(fp_line
			(start -0.12065 -0.305054)
			(end -0.12065 -0.2794)
			(stroke
				(width 0.1)
				(type default)
			)
			(layer "F.Fab")
		)
		(fp_line
			(start -0.67945 -0.305054)
			(end -0.12065 -0.305054)
			(stroke
				(width 0.1)
				(type default)
			)
			(layer "F.Fab")
		)
		(fp_line
			(start 0.67945 -0.3048)
			(end 0.67945 0.3048)
			(stroke
				(width 0.1)
				(type default)
			)
			(layer "F.Fab")
		)
		(fp_line
			(start 0.12065 -0.3048)
			(end 0.67945 -0.3048)
			(stroke
				(width 0.1)
				(type default)
			)
			(layer "F.Fab")
		)
		(fp_line
			(start 0.12065 -0.2794)
			(end 0.12065 -0.3048)
			(stroke
				(width 0.1)
				(type default)
			)
			(layer "F.Fab")
		)
		(fp_line
			(start -0.12065 -0.2794)
			(end 0.12065 -0.2794)
			(stroke
				(width 0.1)
				(type default)
			)
			(layer "F.Fab")
		)
		(fp_line
			(start 0.120396 0.2794)
			(end -0.12065 0.2794)
			(stroke
				(width 0.1)
				(type default)
			)
			(layer "F.Fab")
		)
		(fp_line
			(start -0.12065 0.2794)
			(end -0.12065 0.3048)
			(stroke
				(width 0.1)
				(type default)
			)
			(layer "F.Fab")
		)
		(fp_line
			(start 0.67945 0.3048)
			(end 0.120396 0.3048)
			(stroke
				(width 0.1)
				(type default)
			)
			(layer "F.Fab")
		)
		(fp_line
			(start 0.120396 0.3048)
			(end 0.120396 0.2794)
			(stroke
				(width 0.1)
				(type default)
			)
			(layer "F.Fab")
		)
		(fp_line
			(start -0.12065 0.3048)
			(end -0.67945 0.3048)
			(stroke
				(width 0.1)
				(type default)
			)
			(layer "F.Fab")
		)
		(fp_line
			(start -0.67945 0.3048)
			(end -0.67945 -0.305054)
			(stroke
				(width 0.1)
				(type default)
			)
			(layer "F.Fab")
		)
		(pad "1" smd circle
			(at -0.40005 0 90)
			(size 0 0)
			(layers "F.Cu" "F.Mask" "F.Paste")
			(net "P3V3_AUX")
		)
		(pad "2" smd circle
			(at 0.40005 0 90)
			(size 0 0)
			(layers "F.Cu" "F.Mask" "F.Paste")
			(net "HPDB_HSC_PWRGD_ISO")
		)
	)
	(footprint ""
		(layer "F.Cu")
		(at 160.83788 -113.756948)
		(property "Reference" "R3484"
			(at 0 0 0)
			(layer "F.SilkS")
			(hide yes)
			(effects
				(font
					(size 1.27 1.27)
				)
			)
		)
		(property "Value" ""
			(at 0 0 0)
			(layer "F.Fab")
			(effects
				(font
					(size 1.27 1.27)
				)
			)
		)
		(duplicate_pad_numbers_are_jumpers no)
		(fp_line
			(start -0.7874 -0.4064)
			(end 0.7874 -0.4064)
			(stroke
				(width 0.1524)
				(type default)
			)
			(layer "F.SilkS")
		)
		(fp_line
			(start -0.7874 0.4064)
			(end -0.7874 -0.4064)
			(stroke
				(width 0.1524)
				(type default)
			)
			(layer "F.SilkS")
		)
		(fp_line
			(start 0.7874 -0.4064)
			(end 0.7874 0.4064)
			(stroke
				(width 0.1524)
				(type default)
			)
			(layer "F.SilkS")
		)
		(fp_line
			(start 0.7874 0.4064)
			(end -0.7874 0.4064)
			(stroke
				(width 0.1524)
				(type default)
			)
			(layer "F.SilkS")
		)
		(fp_line
			(start -0.67945 -0.305054)
			(end -0.12065 -0.305054)
			(stroke
				(width 0.1)
				(type default)
			)
			(layer "F.Fab")
		)
		(fp_line
			(start -0.67945 0.3048)
			(end -0.67945 -0.305054)
			(stroke
				(width 0.1)
				(type default)
			)
			(layer "F.Fab")
		)
		(fp_line
			(start -0.12065 -0.305054)
			(end -0.12065 -0.2794)
			(stroke
				(width 0.1)
				(type default)
			)
			(layer "F.Fab")
		)
		(fp_line
			(start -0.12065 -0.2794)
			(end 0.12065 -0.2794)
			(stroke
				(width 0.1)
				(type default)
			)
			(layer "F.Fab")
		)
		(fp_line
			(start -0.12065 0.2794)
			(end -0.12065 0.3048)
			(stroke
				(width 0.1)
				(type default)
			)
			(layer "F.Fab")
		)
		(fp_line
			(start -0.12065 0.3048)
			(end -0.67945 0.3048)
			(stroke
				(width 0.1)
				(type default)
			)
			(layer "F.Fab")
		)
		(fp_line
			(start 0.120396 0.2794)
			(end -0.12065 0.2794)
			(stroke
				(width 0.1)
				(type default)
			)
			(layer "F.Fab")
		)
		(fp_line
			(start 0.120396 0.3048)
			(end 0.120396 0.2794)
			(stroke
				(width 0.1)
				(type default)
			)
			(layer "F.Fab")
		)
		(fp_line
			(start 0.12065 -0.3048)
			(end 0.67945 -0.3048)
			(stroke
				(width 0.1)
				(type default)
			)
			(layer "F.Fab")
		)
		(fp_line
			(start 0.12065 -0.2794)
			(end 0.12065 -0.3048)
			(stroke
				(width 0.1)
				(type default)
			)
			(layer "F.Fab")
		)
		(fp_line
			(start 0.67945 -0.3048)
			(end 0.67945 0.3048)
			(stroke
				(width 0.1)
				(type default)
			)
			(layer "F.Fab")
		)
		(fp_line
			(start 0.67945 0.3048)
			(end 0.120396 0.3048)
			(stroke
				(width 0.1)
				(type default)
			)
			(layer "F.Fab")
		)
		(pad "1" smd circle
			(at -0.40005 0)
			(size 0 0)
			(layers "F.Cu" "F.Mask" "F.Paste")
			(net "GPU_FPGA_OVERT_ISO_N")
		)
		(pad "2" smd circle
			(at 0.40005 0)
			(size 0 0)
			(layers "F.Cu" "F.Mask" "F.Paste")
			(net "GPU_FPGA_OVERT_ISO_R_N")
		)
	)
)
